(kicad_pcb
	(version 20260206)
	(generator "pcbnew")
	(generator_version "10.0")
	(general
		(thickness 1.6)
		(legacy_teardrops no)
	)
	(paper "A4")
	(title_block
		(title "03242023_DA0F0TMBIJ0_F0T_Motherboard_J_brd_V01_OCP.brd")
		(comment 1 "Grand Teton / footprints 1668-1672 of 6105")
	)
	(layers
		(0 "F.Cu" signal "TOP")
		(4 "In1.Cu" signal "GND")
		(6 "In2.Cu" signal "IN1")
		(8 "In3.Cu" signal "GND1")
		(10 "In4.Cu" signal "IN2")
		(12 "In5.Cu" signal "GND2")
		(14 "In6.Cu" signal "IN3")
		(16 "In7.Cu" signal "GND3")
		(18 "In8.Cu" signal "VCC")
		(20 "In9.Cu" signal "VCC1")
		(22 "In10.Cu" signal "GND4")
		(24 "In11.Cu" signal "IN4")
		(26 "In12.Cu" signal "GND5")
		(28 "In13.Cu" signal "IN5")
		(30 "In14.Cu" signal "GND6")
		(32 "In15.Cu" signal "IN6")
		(34 "In16.Cu" signal "GND7")
		(2 "B.Cu" signal "BOTTOM")
		(9 "F.Adhes" user "F.Adhesive")
		(11 "B.Adhes" user "B.Adhesive")
		(13 "F.Paste" user "Package Geometry/Pastemask Top")
		(15 "B.Paste" user "Package Geometry/Pastemask Bottom")
		(5 "F.SilkS" user "Ref Des/Silkscreen Top")
		(7 "B.SilkS" user "Ref Des/Silkscreen Bottom")
		(1 "F.Mask" user "Board Geometry/Soldermask Top")
		(3 "B.Mask" user "Board Geometry/Soldermask Bottom")
		(17 "Dwgs.User" user "User.Drawings")
		(19 "Cmts.User" user "User.Comments")
		(21 "Eco1.User" user "User.Eco1")
		(23 "Eco2.User" user "User.Eco2")
		(25 "Edge.Cuts" user "Board Geometry/Outline")
		(27 "Margin" user)
		(31 "F.CrtYd" user "Package Geometry/Place Bound Top")
		(29 "B.CrtYd" user "Package Geometry/Place Bound Bottom")
		(35 "F.Fab" user "Ref Des/Assembly Top")
		(33 "B.Fab" user "Ref Des/Assembly Bottom")
	)
	(footprint ""
		(layer "F.Cu")
		(at 52.423314 -161.539174 180)
		(property "Reference" "PC373"
			(at 0 0 180)
			(layer "F.SilkS")
			(hide yes)
			(effects
				(font
					(size 1.27 1.27)
				)
			)
		)
		(property "Value" ""
			(at 0 0 180)
			(layer "F.Fab")
			(effects
				(font
					(size 1.27 1.27)
				)
			)
		)
		(duplicate_pad_numbers_are_jumpers no)
		(fp_line
			(start 0.7874 0.4064)
			(end -0.7874 0.4064)
			(stroke
				(width 0.1524)
				(type default)
			)
			(layer "F.SilkS")
		)
		(fp_line
			(start 0.7874 -0.4064)
			(end 0.7874 0.4064)
			(stroke
				(width 0.1524)
				(type default)
			)
			(layer "F.SilkS")
		)
		(fp_line
			(start -0.7874 0.4064)
			(end -0.7874 -0.4064)
			(stroke
				(width 0.1524)
				(type default)
			)
			(layer "F.SilkS")
		)
		(fp_line
			(start -0.7874 -0.4064)
			(end 0.7874 -0.4064)
			(stroke
				(width 0.1524)
				(type default)
			)
			(layer "F.SilkS")
		)
		(fp_line
			(start 0.67945 0.3048)
			(end 0.120396 0.3048)
			(stroke
				(width 0.1)
				(type default)
			)
			(layer "F.Fab")
		)
		(fp_line
			(start 0.67945 -0.3048)
			(end 0.67945 0.3048)
			(stroke
				(width 0.1)
				(type default)
			)
			(layer "F.Fab")
		)
		(fp_line
			(start 0.12065 -0.2794)
			(end 0.12065 -0.3048)
			(stroke
				(width 0.1)
				(type default)
			)
			(layer "F.Fab")
		)
		(fp_line
			(start 0.12065 -0.3048)
			(end 0.67945 -0.3048)
			(stroke
				(width 0.1)
				(type default)
			)
			(layer "F.Fab")
		)
		(fp_line
			(start 0.120396 0.3048)
			(end 0.120396 0.2794)
			(stroke
				(width 0.1)
				(type default)
			)
			(layer "F.Fab")
		)
		(fp_line
			(start 0.120396 0.2794)
			(end -0.12065 0.2794)
			(stroke
				(width 0.1)
				(type default)
			)
			(layer "F.Fab")
		)
		(fp_line
			(start -0.12065 0.3048)
			(end -0.67945 0.3048)
			(stroke
				(width 0.1)
				(type default)
			)
			(layer "F.Fab")
		)
		(fp_line
			(start -0.12065 0.2794)
			(end -0.12065 0.3048)
			(stroke
				(width 0.1)
				(type default)
			)
			(layer "F.Fab")
		)
		(fp_line
			(start -0.12065 -0.2794)
			(end 0.12065 -0.2794)
			(stroke
				(width 0.1)
				(type default)
			)
			(layer "F.Fab")
		)
		(fp_line
			(start -0.12065 -0.305054)
			(end -0.12065 -0.2794)
			(stroke
				(width 0.1)
				(type default)
			)
			(layer "F.Fab")
		)
		(fp_line
			(start -0.67945 0.3048)
			(end -0.67945 -0.305054)
			(stroke
				(width 0.1)
				(type default)
			)
			(layer "F.Fab")
		)
		(fp_line
			(start -0.67945 -0.305054)
			(end -0.12065 -0.305054)
			(stroke
				(width 0.1)
				(type default)
			)
			(layer "F.Fab")
		)
		(pad "1" smd circle
			(at -0.40005 0 180)
			(size 0 0)
			(layers "F.Cu" "F.Mask" "F.Paste")
			(net "PVCCD_HV_CPU1_VDD1")
		)
		(pad "2" smd circle
			(at 0.40005 0 180)
			(size 0 0)
			(layers "F.Cu" "F.Mask" "F.Paste")
			(net "GND")
		)
	)
	(footprint ""
		(layer "F.Cu")
		(at 9.652 -51.018948)
		(property "Reference" "R3052"
			(at 0 0 0)
			(layer "F.SilkS")
			(hide yes)
			(effects
				(font
					(size 1.27 1.27)
				)
			)
		)
		(property "Value" ""
			(at 0 0 0)
			(layer "F.Fab")
			(effects
				(font
					(size 1.27 1.27)
				)
			)
		)
		(duplicate_pad_numbers_are_jumpers no)
		(fp_line
			(start -0.7874 -0.4064)
			(end 0.7874 -0.4064)
			(stroke
				(width 0.1524)
				(type default)
			)
			(layer "F.SilkS")
		)
		(fp_line
			(start -0.7874 0.4064)
			(end -0.7874 -0.4064)
			(stroke
				(width 0.1524)
				(type default)
			)
			(layer "F.SilkS")
		)
		(fp_line
			(start 0.7874 -0.4064)
			(end 0.7874 0.4064)
			(stroke
				(width 0.1524)
				(type default)
			)
			(layer "F.SilkS")
		)
		(fp_line
			(start 0.7874 0.4064)
			(end -0.7874 0.4064)
			(stroke
				(width 0.1524)
				(type default)
			)
			(layer "F.SilkS")
		)
		(fp_line
			(start -0.67945 -0.305054)
			(end -0.12065 -0.305054)
			(stroke
				(width 0.1)
				(type default)
			)
			(layer "F.Fab")
		)
		(fp_line
			(start -0.67945 0.3048)
			(end -0.67945 -0.305054)
			(stroke
				(width 0.1)
				(type default)
			)
			(layer "F.Fab")
		)
		(fp_line
			(start -0.12065 -0.305054)
			(end -0.12065 -0.2794)
			(stroke
				(width 0.1)
				(type default)
			)
			(layer "F.Fab")
		)
		(fp_line
			(start -0.12065 -0.2794)
			(end 0.12065 -0.2794)
			(stroke
				(width 0.1)
				(type default)
			)
			(layer "F.Fab")
		)
		(fp_line
			(start -0.12065 0.2794)
			(end -0.12065 0.3048)
			(stroke
				(width 0.1)
				(type default)
			)
			(layer "F.Fab")
		)
		(fp_line
			(start -0.12065 0.3048)
			(end -0.67945 0.3048)
			(stroke
				(width 0.1)
				(type default)
			)
			(layer "F.Fab")
		)
		(fp_line
			(start 0.120396 0.2794)
			(end -0.12065 0.2794)
			(stroke
				(width 0.1)
				(type default)
			)
			(layer "F.Fab")
		)
		(fp_line
			(start 0.120396 0.3048)
			(end 0.120396 0.2794)
			(stroke
				(width 0.1)
				(type default)
			)
			(layer "F.Fab")
		)
		(fp_line
			(start 0.12065 -0.3048)
			(end 0.67945 -0.3048)
			(stroke
				(width 0.1)
				(type default)
			)
			(layer "F.Fab")
		)
		(fp_line
			(start 0.12065 -0.2794)
			(end 0.12065 -0.3048)
			(stroke
				(width 0.1)
				(type default)
			)
			(layer "F.Fab")
		)
		(fp_line
			(start 0.67945 -0.3048)
			(end 0.67945 0.3048)
			(stroke
				(width 0.1)
				(type default)
			)
			(layer "F.Fab")
		)
		(fp_line
			(start 0.67945 0.3048)
			(end 0.120396 0.3048)
			(stroke
				(width 0.1)
				(type default)
			)
			(layer "F.Fab")
		)
		(pad "1" smd circle
			(at -0.40005 0)
			(size 0 0)
			(layers "F.Cu" "F.Mask" "F.Paste")
			(net "SMB_HOST_3V3AUX_SCL_R5")
		)
		(pad "2" smd circle
			(at 0.40005 0)
			(size 0 0)
			(layers "F.Cu" "F.Mask" "F.Paste")
			(net "SMB_HOST_ME_SCL")
		)
	)
	(footprint ""
		(layer "F.Cu")
		(at 155.348686 -81.89468 90)
		(property "Reference" "R3123"
			(at 0 0 90)
			(layer "F.SilkS")
			(hide yes)
			(effects
				(font
					(size 1.27 1.27)
				)
			)
		)
		(property "Value" ""
			(at 0 0 90)
			(layer "F.Fab")
			(effects
				(font
					(size 1.27 1.27)
				)
			)
		)
		(duplicate_pad_numbers_are_jumpers no)
		(fp_line
			(start 0.7874 -0.4064)
			(end 0.7874 0.4064)
			(stroke
				(width 0.1524)
				(type default)
			)
			(layer "F.SilkS")
		)
		(fp_line
			(start -0.7874 -0.4064)
			(end 0.7874 -0.4064)
			(stroke
				(width 0.1524)
				(type default)
			)
			(layer "F.SilkS")
		)
		(fp_line
			(start 0.7874 0.4064)
			(end -0.7874 0.4064)
			(stroke
				(width 0.1524)
				(type default)
			)
			(layer "F.SilkS")
		)
		(fp_line
			(start -0.7874 0.4064)
			(end -0.7874 -0.4064)
			(stroke
				(width 0.1524)
				(type default)
			)
			(layer "F.SilkS")
		)
		(fp_line
			(start -0.12065 -0.305054)
			(end -0.12065 -0.2794)
			(stroke
				(width 0.1)
				(type default)
			)
			(layer "F.Fab")
		)
		(fp_line
			(start -0.67945 -0.305054)
			(end -0.12065 -0.305054)
			(stroke
				(width 0.1)
				(type default)
			)
			(layer "F.Fab")
		)
		(fp_line
			(start 0.67945 -0.3048)
			(end 0.67945 0.3048)
			(stroke
				(width 0.1)
				(type default)
			)
			(layer "F.Fab")
		)
		(fp_line
			(start 0.12065 -0.3048)
			(end 0.67945 -0.3048)
			(stroke
				(width 0.1)
				(type default)
			)
			(layer "F.Fab")
		)
		(fp_line
			(start 0.12065 -0.2794)
			(end 0.12065 -0.3048)
			(stroke
				(width 0.1)
				(type default)
			)
			(layer "F.Fab")
		)
		(fp_line
			(start -0.12065 -0.2794)
			(end 0.12065 -0.2794)
			(stroke
				(width 0.1)
				(type default)
			)
			(layer "F.Fab")
		)
		(fp_line
			(start 0.120396 0.2794)
			(end -0.12065 0.2794)
			(stroke
				(width 0.1)
				(type default)
			)
			(layer "F.Fab")
		)
		(fp_line
			(start -0.12065 0.2794)
			(end -0.12065 0.3048)
			(stroke
				(width 0.1)
				(type default)
			)
			(layer "F.Fab")
		)
		(fp_line
			(start 0.67945 0.3048)
			(end 0.120396 0.3048)
			(stroke
				(width 0.1)
				(type default)
			)
			(layer "F.Fab")
		)
		(fp_line
			(start 0.120396 0.3048)
			(end 0.120396 0.2794)
			(stroke
				(width 0.1)
				(type default)
			)
			(layer "F.Fab")
		)
		(fp_line
			(start -0.12065 0.3048)
			(end -0.67945 0.3048)
			(stroke
				(width 0.1)
				(type default)
			)
			(layer "F.Fab")
		)
		(fp_line
			(start -0.67945 0.3048)
			(end -0.67945 -0.305054)
			(stroke
				(width 0.1)
				(type default)
			)
			(layer "F.Fab")
		)
		(pad "1" smd circle
			(at -0.40005 0 90)
			(size 0 0)
			(layers "F.Cu" "F.Mask" "F.Paste")
			(net "SMB_S3M_CPU0_PIROM_3V3AUX_SCL_R")
		)
		(pad "2" smd circle
			(at 0.40005 0 90)
			(size 0 0)
			(layers "F.Cu" "F.Mask" "F.Paste")
			(net "SMB_S3M_CPU0_PIROM_3V3AUX_SCL")
		)
	)
	(footprint ""
		(layer "F.Cu")
		(at 18.753582 -423.629836 -90)
		(property "Reference" "R3518"
			(at 0 0 270)
			(layer "F.SilkS")
			(hide yes)
			(effects
				(font
					(size 1.27 1.27)
				)
			)
		)
		(property "Value" ""
			(at 0 0 270)
			(layer "F.Fab")
			(effects
				(font
					(size 1.27 1.27)
				)
			)
		)
		(duplicate_pad_numbers_are_jumpers no)
		(fp_line
			(start -0.7874 0.4064)
			(end -0.7874 -0.4064)
			(stroke
				(width 0.1524)
				(type default)
			)
			(layer "F.SilkS")
		)
		(fp_line
			(start 0.7874 0.4064)
			(end -0.7874 0.4064)
			(stroke
				(width 0.1524)
				(type default)
			)
			(layer "F.SilkS")
		)
		(fp_line
			(start -0.7874 -0.4064)
			(end 0.7874 -0.4064)
			(stroke
				(width 0.1524)
				(type default)
			)
			(layer "F.SilkS")
		)
		(fp_line
			(start 0.7874 -0.4064)
			(end 0.7874 0.4064)
			(stroke
				(width 0.1524)
				(type default)
			)
			(layer "F.SilkS")
		)
		(fp_line
			(start -0.67945 0.3048)
			(end -0.67945 -0.305054)
			(stroke
				(width 0.1)
				(type default)
			)
			(layer "F.Fab")
		)
		(fp_line
			(start -0.12065 0.3048)
			(end -0.67945 0.3048)
			(stroke
				(width 0.1)
				(type default)
			)
			(layer "F.Fab")
		)
		(fp_line
			(start 0.120396 0.3048)
			(end 0.120396 0.2794)
			(stroke
				(width 0.1)
				(type default)
			)
			(layer "F.Fab")
		)
		(fp_line
			(start 0.67945 0.3048)
			(end 0.120396 0.3048)
			(stroke
				(width 0.1)
				(type default)
			)
			(layer "F.Fab")
		)
		(fp_line
			(start -0.12065 0.2794)
			(end -0.12065 0.3048)
			(stroke
				(width 0.1)
				(type default)
			)
			(layer "F.Fab")
		)
		(fp_line
			(start 0.120396 0.2794)
			(end -0.12065 0.2794)
			(stroke
				(width 0.1)
				(type default)
			)
			(layer "F.Fab")
		)
		(fp_line
			(start -0.12065 -0.2794)
			(end 0.12065 -0.2794)
			(stroke
				(width 0.1)
				(type default)
			)
			(layer "F.Fab")
		)
		(fp_line
			(start 0.12065 -0.2794)
			(end 0.12065 -0.3048)
			(stroke
				(width 0.1)
				(type default)
			)
			(layer "F.Fab")
		)
		(fp_line
			(start 0.12065 -0.3048)
			(end 0.67945 -0.3048)
			(stroke
				(width 0.1)
				(type default)
			)
			(layer "F.Fab")
		)
		(fp_line
			(start 0.67945 -0.3048)
			(end 0.67945 0.3048)
			(stroke
				(width 0.1)
				(type default)
			)
			(layer "F.Fab")
		)
		(fp_line
			(start -0.67945 -0.305054)
			(end -0.12065 -0.305054)
			(stroke
				(width 0.1)
				(type default)
			)
			(layer "F.Fab")
		)
		(fp_line
			(start -0.12065 -0.305054)
			(end -0.12065 -0.2794)
			(stroke
				(width 0.1)
				(type default)
			)
			(layer "F.Fab")
		)
		(pad "1" smd circle
			(at -0.40005 0 270)
			(size 0 0)
			(layers "F.Cu" "F.Mask" "F.Paste")
			(net "GPU_PEX_STRAP0")
		)
		(pad "2" smd circle
			(at 0.40005 0 270)
			(size 0 0)
			(layers "F.Cu" "F.Mask" "F.Paste")
			(net "GPU_PEX_STRAP0_R")
		)
	)
	(footprint ""
		(layer "F.Cu")
		(at 115.219734 -95.504762 -90)
		(property "Reference" "U301"
			(at -0.353568 -3.017266 0)
			(unlocked yes)
			(layer "F.SilkS")
			(effects
				(font
					(size 0.7874 0.5842)
					(thickness 0.1524)
				)
				(justify left)
			)
		)
		(property "Value" ""
			(at 0 0 270)
			(layer "F.Fab")
			(effects
				(font
					(size 1.27 1.27)
				)
			)
		)
		(duplicate_pad_numbers_are_jumpers no)
		(fp_line
			(start -2.0066 2.5527)
			(end -2.0066 -2.5527)
			(stroke
				(width 0.1524)
				(type default)
			)
			(layer "F.SilkS")
		)
		(fp_line
			(start 2.0066 2.5527)
			(end -2.0066 2.5527)
			(stroke
				(width 0.1524)
				(type default)
			)
			(layer "F.SilkS")
		)
		(fp_line
			(start 0 -1.9812)
			(end 0.5715 -2.5527)
			(stroke
				(width 0.1524)
				(type default)
			)
			(layer "F.SilkS")
		)
		(fp_line
			(start -2.0066 -2.5527)
			(end -0.5715 -2.5527)
			(stroke
				(width 0.1524)
				(type default)
			)
			(layer "F.SilkS")
		)
		(fp_line
			(start -0.5715 -2.5527)
			(end 0 -1.9812)
			(stroke
				(width 0.1524)
				(type default)
			)
			(layer "F.SilkS")
		)
		(fp_line
			(start 0.5715 -2.5527)
			(end 2.0066 -2.5527)
			(stroke
				(width 0.1524)
				(type default)
			)
			(layer "F.SilkS")
		)
		(fp_line
			(start 2.0066 -2.5527)
			(end 2.0066 2.5527)
			(stroke
				(width 0.1524)
				(type default)
			)
			(layer "F.SilkS")
		)
		(fp_poly
			(pts
				(xy -2.958084 -2.921) (xy -3.286252 -2.36728) (xy -3.582924 -2.921)
			)
			(stroke
				(width 0)
				(type default)
			)
			(fill yes)
			(layer "F.SilkS")
		)
		(fp_line
			(start -2.249932 2.549906)
			(end -2.249932 -2.549906)
			(stroke
				(width 0.1)
				(type default)
			)
			(layer "F.Fab")
		)
		(fp_line
			(start 2.249932 2.549906)
			(end -2.249932 2.549906)
			(stroke
				(width 0.1)
				(type default)
			)
			(layer "F.Fab")
		)
		(fp_line
			(start -2.249932 -2.549906)
			(end 2.249932 -2.549906)
			(stroke
				(width 0.1)
				(type default)
			)
			(layer "F.Fab")
		)
		(fp_line
			(start 2.249932 -2.549906)
			(end 2.249932 2.549906)
			(stroke
				(width 0.1)
				(type default)
			)
			(layer "F.Fab")
		)
		(fp_poly
			(pts
				(xy -4.36372 -1.608328) (xy -4.36372 -2.233168) (xy -3.81 -1.905)
			)
			(stroke
				(width 0)
				(type default)
			)
			(fill yes)
			(layer "F.Fab")
		)
		(pad "1" smd rect
			(at -2.921 -1.949958 180)
			(size 0.3556 1.4986)
			(layers "F.Cu" "F.Mask" "F.Paste")
			(net "PD_CPU0_ERRS_DIR")
		)
		(pad "2" smd rect
			(at -2.921 -1.299972 180)
			(size 0.3556 1.4986)
			(layers "F.Cu" "F.Mask" "F.Paste")
			(net "H_CPU_CATERR_LVC1_R_N")
		)
		(pad "3" smd rect
			(at -2.921 -0.649986 180)
			(size 0.3556 1.4986)
			(layers "F.Cu" "F.Mask" "F.Paste")
			(net "H_CPU_CATERR_LVC1_R_N")
		)
		(pad "4" smd rect
			(at -2.921 0 180)
			(size 0.3556 1.4986)
			(layers "F.Cu" "F.Mask" "F.Paste")
			(net "P0V62_CPU0_ERRS_VREF")
		)
		(pad "5" smd rect
			(at -2.921 0.649986 180)
			(size 0.3556 1.4986)
			(layers "F.Cu" "F.Mask" "F.Paste")
			(net "H_CPU_RMCA_LVC1_R_N")
		)
		(pad "6" smd rect
			(at -2.921 1.299972 180)
			(size 0.3556 1.4986)
			(layers "F.Cu" "F.Mask" "F.Paste")
			(net "PWRGD_CPUPWRGD_LVC1")
		)
		(pad "7" smd rect
			(at -2.921 1.949958 180)
			(size 0.3556 1.4986)
			(layers "F.Cu" "F.Mask" "F.Paste")
			(net "GND")
		)
		(pad "8" smd rect
			(at 2.921 1.949958 180)
			(size 0.3556 1.4986)
			(layers "F.Cu" "F.Mask" "F.Paste")
			(net "GND")
		)
		(pad "9" smd rect
			(at 2.921 1.299972 180)
			(size 0.3556 1.4986)
			(layers "F.Cu" "F.Mask" "F.Paste")
			(net "PWRGD_CPUPWRGD_LVC2_R")
		)
		(pad "10" smd rect
			(at 2.921 0.649986 180)
			(size 0.3556 1.4986)
			(layers "F.Cu" "F.Mask" "F.Paste")
			(net "H_CPU_RMCA_LVC2_R1_N")
		)
		(pad "11" smd rect
			(at 2.921 0 180)
			(size 0.3556 1.4986)
			(layers "F.Cu" "F.Mask" "F.Paste")
			(net "GND")
		)
		(pad "12" smd rect
			(at 2.921 -0.649986 180)
			(size 0.3556 1.4986)
			(layers "F.Cu" "F.Mask" "F.Paste")
			(net "H_CPU_CATERR_LVC2_R1_N")
		)
		(pad "13" smd rect
			(at 2.921 -1.299972 180)
			(size 0.3556 1.4986)
			(layers "F.Cu" "F.Mask" "F.Paste")
			(net "H_CPU_CATERR_LVC2_BMC_R_N")
		)
		(pad "14" smd rect
			(at 2.921 -1.949958 180)
			(size 0.3556 1.4986)
			(layers "F.Cu" "F.Mask" "F.Paste")
			(net "P3V3")
		)
	)
)
